# S9S_MB_2U (Grand Teton) — schematic netlist excerpt (pin names and nets, part order shuffled) for the footprints in the layout excerpt that follows; sources: Cadence DE-HDL packaged netlist, KiCad conversion of 03242023_DA0F0TMBIJ0_F0T_Motherboard_J_brd_V01_OCP.brd

R4691  Q_RES  0 5% EMPTY  pkg 0402LF  page 251 : A = HSC_TYPE_ADC_A0 ; B = SMB_HSC_TYPE_ADC_SDA
C372  Q_CAP  47UF 4V 20% X6S  pkg C0805  page 76 : A = PVCCIN_CPU0 ; B = GND
C211  Q_CAP  0.1UF 25V 10% X7R  pkg 0402  page 206 : A = P3V3_DB2000_VDDA ; B = GND

(kicad_pcb
	(version 20260206)
	(generator "pcbnew")
	(generator_version "10.0")
	(general
		(thickness 1.6)
		(legacy_teardrops no)
	)
	(paper "A4")
	(title_block
		(title "03242023_DA0F0TMBIJ0_F0T_Motherboard_J_brd_V01_OCP.brd")
		(comment 1 "Grand Teton / footprints 5370-5372 of 6105")
	)
	(layers
		(0 "F.Cu" signal "TOP")
		(4 "In1.Cu" signal "GND")
		(6 "In2.Cu" signal "IN1")
		(8 "In3.Cu" signal "GND1")
		(10 "In4.Cu" signal "IN2")
		(12 "In5.Cu" signal "GND2")
		(14 "In6.Cu" signal "IN3")
		(16 "In7.Cu" signal "GND3")
		(18 "In8.Cu" signal "VCC")
		(20 "In9.Cu" signal "VCC1")
		(22 "In10.Cu" signal "GND4")
		(24 "In11.Cu" signal "IN4")
		(26 "In12.Cu" signal "GND5")
		(28 "In13.Cu" signal "IN5")
		(30 "In14.Cu" signal "GND6")
		(32 "In15.Cu" signal "IN6")
		(34 "In16.Cu" signal "GND7")
		(2 "B.Cu" signal "BOTTOM")
		(9 "F.Adhes" user "F.Adhesive")
		(11 "B.Adhes" user "B.Adhesive")
		(13 "F.Paste" user "Package Geometry/Pastemask Top")
		(15 "B.Paste" user "Package Geometry/Pastemask Bottom")
		(5 "F.SilkS" user "Ref Des/Silkscreen Top")
		(7 "B.SilkS" user "Ref Des/Silkscreen Bottom")
		(1 "F.Mask" user "Board Geometry/Soldermask Top")
		(3 "B.Mask" user "Board Geometry/Soldermask Bottom")
		(17 "Dwgs.User" user "User.Drawings")
		(19 "Cmts.User" user "User.Comments")
		(21 "Eco1.User" user "User.Eco1")
		(23 "Eco2.User" user "User.Eco2")
		(25 "Edge.Cuts" user "Board Geometry/Outline")
		(27 "Margin" user)
		(31 "F.CrtYd" user "Package Geometry/Place Bound Top")
		(29 "B.CrtYd" user "Package Geometry/Place Bound Bottom")
		(35 "F.Fab" user "Ref Des/Assembly Top")
		(33 "B.Fab" user "Ref Des/Assembly Bottom")
	)
	(footprint ""
		(layer "B.Cu")
		(at 294.71874 -413.95904 90)
		(property "Reference" "R4691"
			(at 0 0 90)
			(layer "B.SilkS")
			(hide yes)
			(effects
				(font
					(size 1.27 1.27)
				)
				(justify mirror)
			)
		)
		(property "Value" ""
			(at 0 0 90)
			(layer "B.Fab")
			(effects
				(font
					(size 1.27 1.27)
				)
				(justify mirror)
			)
		)
		(duplicate_pad_numbers_are_jumpers no)
		(fp_line
			(start 0.7874 -0.4064)
			(end -0.7874 -0.4064)
			(stroke
				(width 0.1524)
				(type default)
			)
			(layer "B.SilkS")
		)
		(fp_line
			(start -0.7874 -0.4064)
			(end -0.7874 0.4064)
			(stroke
				(width 0.1524)
				(type default)
			)
			(layer "B.SilkS")
		)
		(fp_line
			(start 0.7874 0.4064)
			(end 0.7874 -0.4064)
			(stroke
				(width 0.1524)
				(type default)
			)
			(layer "B.SilkS")
		)
		(fp_line
			(start -0.7874 0.4064)
			(end 0.7874 0.4064)
			(stroke
				(width 0.1524)
				(type default)
			)
			(layer "B.SilkS")
		)
		(fp_line
			(start 0.67945 -0.305054)
			(end 0.12065 -0.305054)
			(stroke
				(width 0.1)
				(type default)
			)
			(layer "B.Fab")
		)
		(fp_line
			(start 0.12065 -0.305054)
			(end 0.12065 -0.2794)
			(stroke
				(width 0.1)
				(type default)
			)
			(layer "B.Fab")
		)
		(fp_line
			(start -0.12065 -0.3048)
			(end -0.67945 -0.3048)
			(stroke
				(width 0.1)
				(type default)
			)
			(layer "B.Fab")
		)
		(fp_line
			(start -0.67945 -0.3048)
			(end -0.67945 0.3048)
			(stroke
				(width 0.1)
				(type default)
			)
			(layer "B.Fab")
		)
		(fp_line
			(start 0.12065 -0.2794)
			(end -0.12065 -0.2794)
			(stroke
				(width 0.1)
				(type default)
			)
			(layer "B.Fab")
		)
		(fp_line
			(start -0.12065 -0.2794)
			(end -0.12065 -0.3048)
			(stroke
				(width 0.1)
				(type default)
			)
			(layer "B.Fab")
		)
		(fp_line
			(start 0.12065 0.2794)
			(end 0.12065 0.3048)
			(stroke
				(width 0.1)
				(type default)
			)
			(layer "B.Fab")
		)
		(fp_line
			(start -0.120396 0.2794)
			(end 0.12065 0.2794)
			(stroke
				(width 0.1)
				(type default)
			)
			(layer "B.Fab")
		)
		(fp_line
			(start 0.67945 0.3048)
			(end 0.67945 -0.305054)
			(stroke
				(width 0.1)
				(type default)
			)
			(layer "B.Fab")
		)
		(fp_line
			(start 0.12065 0.3048)
			(end 0.67945 0.3048)
			(stroke
				(width 0.1)
				(type default)
			)
			(layer "B.Fab")
		)
		(fp_line
			(start -0.120396 0.3048)
			(end -0.120396 0.2794)
			(stroke
				(width 0.1)
				(type default)
			)
			(layer "B.Fab")
		)
		(fp_line
			(start -0.67945 0.3048)
			(end -0.120396 0.3048)
			(stroke
				(width 0.1)
				(type default)
			)
			(layer "B.Fab")
		)
		(pad "1" smd circle
			(at 0.40005 0 270)
			(size 0 0)
			(layers "B.Cu" "B.Mask" "B.Paste")
			(net "HSC_TYPE_ADC_A0")
		)
		(pad "2" smd circle
			(at -0.40005 0 270)
			(size 0 0)
			(layers "B.Cu" "B.Mask" "B.Paste")
			(net "SMB_HSC_TYPE_ADC_SDA")
		)
	)
	(footprint ""
		(layer "B.Cu")
		(at 356.785418 -294.009826 180)
		(property "Reference" "C372"
			(at 0 0 0)
			(layer "B.SilkS")
			(hide yes)
			(effects
				(font
					(size 1.27 1.27)
				)
				(justify mirror)
			)
		)
		(property "Value" ""
			(at 0 0 0)
			(layer "B.Fab")
			(effects
				(font
					(size 1.27 1.27)
				)
				(justify mirror)
			)
		)
		(duplicate_pad_numbers_are_jumpers no)
		(fp_line
			(start 1.524 0.762)
			(end 1.524 -0.762)
			(stroke
				(width 0.1524)
				(type default)
			)
			(layer "B.SilkS")
		)
		(fp_line
			(start 1.524 -0.762)
			(end -1.524 -0.762)
			(stroke
				(width 0.1524)
				(type default)
			)
			(layer "B.SilkS")
		)
		(fp_line
			(start -1.524 0.762)
			(end 1.524 0.762)
			(stroke
				(width 0.1524)
				(type default)
			)
			(layer "B.SilkS")
		)
		(fp_line
			(start -1.524 -0.762)
			(end -1.524 0.762)
			(stroke
				(width 0.1524)
				(type default)
			)
			(layer "B.SilkS")
		)
		(fp_line
			(start 1.1049 0.724916)
			(end -1.1049 0.724916)
			(stroke
				(width 0.1)
				(type default)
			)
			(layer "B.Fab")
		)
		(fp_line
			(start 1.1049 -0.724916)
			(end 1.1049 0.724916)
			(stroke
				(width 0.1)
				(type default)
			)
			(layer "B.Fab")
		)
		(fp_line
			(start -1.1049 0.724916)
			(end -1.1049 -0.724916)
			(stroke
				(width 0.1)
				(type default)
			)
			(layer "B.Fab")
		)
		(fp_line
			(start -1.1049 -0.724916)
			(end 1.1049 -0.724916)
			(stroke
				(width 0.1)
				(type default)
			)
			(layer "B.Fab")
		)
		(pad "1" smd rect
			(at 0.889 0 180)
			(size 1.016 1.27)
			(layers "B.Cu" "B.Mask" "B.Paste")
			(net "PVCCIN_CPU0")
		)
		(pad "2" smd rect
			(at -0.889 0 180)
			(size 1.016 1.27)
			(layers "B.Cu" "B.Mask" "B.Paste")
			(net "GND")
		)
	)
	(footprint ""
		(layer "B.Cu")
		(at 235.955332 -123.453652 90)
		(property "Reference" "C211"
			(at 0 0 90)
			(layer "B.SilkS")
			(hide yes)
			(effects
				(font
					(size 1.27 1.27)
				)
				(justify mirror)
			)
		)
		(property "Value" ""
			(at 0 0 90)
			(layer "B.Fab")
			(effects
				(font
					(size 1.27 1.27)
				)
				(justify mirror)
			)
		)
		(duplicate_pad_numbers_are_jumpers no)
		(fp_line
			(start 0.7874 -0.4064)
			(end -0.7874 -0.4064)
			(stroke
				(width 0.1524)
				(type default)
			)
			(layer "B.SilkS")
		)
		(fp_line
			(start -0.7874 -0.4064)
			(end -0.7874 0.4064)
			(stroke
				(width 0.1524)
				(type default)
			)
			(layer "B.SilkS")
		)
		(fp_line
			(start 0.7874 0.4064)
			(end 0.7874 -0.4064)
			(stroke
				(width 0.1524)
				(type default)
			)
			(layer "B.SilkS")
		)
		(fp_line
			(start -0.7874 0.4064)
			(end 0.7874 0.4064)
			(stroke
				(width 0.1524)
				(type default)
			)
			(layer "B.SilkS")
		)
		(fp_line
			(start 0.67945 -0.305054)
			(end 0.12065 -0.305054)
			(stroke
				(width 0.1)
				(type default)
			)
			(layer "B.Fab")
		)
		(fp_line
			(start 0.12065 -0.305054)
			(end 0.12065 -0.2794)
			(stroke
				(width 0.1)
				(type default)
			)
			(layer "B.Fab")
		)
		(fp_line
			(start -0.12065 -0.3048)
			(end -0.67945 -0.3048)
			(stroke
				(width 0.1)
				(type default)
			)
			(layer "B.Fab")
		)
		(fp_line
			(start -0.67945 -0.3048)
			(end -0.67945 0.3048)
			(stroke
				(width 0.1)
				(type default)
			)
			(layer "B.Fab")
		)
		(fp_line
			(start 0.12065 -0.2794)
			(end -0.12065 -0.2794)
			(stroke
				(width 0.1)
				(type default)
			)
			(layer "B.Fab")
		)
		(fp_line
			(start -0.12065 -0.2794)
			(end -0.12065 -0.3048)
			(stroke
				(width 0.1)
				(type default)
			)
			(layer "B.Fab")
		)
		(fp_line
			(start 0.12065 0.2794)
			(end 0.12065 0.3048)
			(stroke
				(width 0.1)
				(type default)
			)
			(layer "B.Fab")
		)
		(fp_line
			(start -0.120396 0.2794)
			(end 0.12065 0.2794)
			(stroke
				(width 0.1)
				(type default)
			)
			(layer "B.Fab")
		)
		(fp_line
			(start 0.67945 0.3048)
			(end 0.67945 -0.305054)
			(stroke
				(width 0.1)
				(type default)
			)
			(layer "B.Fab")
		)
		(fp_line
			(start 0.12065 0.3048)
			(end 0.67945 0.3048)
			(stroke
				(width 0.1)
				(type default)
			)
			(layer "B.Fab")
		)
		(fp_line
			(start -0.120396 0.3048)
			(end -0.120396 0.2794)
			(stroke
				(width 0.1)
				(type default)
			)
			(layer "B.Fab")
		)
		(fp_line
			(start -0.67945 0.3048)
			(end -0.120396 0.3048)
			(stroke
				(width 0.1)
				(type default)
			)
			(layer "B.Fab")
		)
		(pad "1" smd circle
			(at 0.40005 0 270)
			(size 0 0)
			(layers "B.Cu" "B.Mask" "B.Paste")
			(net "P3V3_DB2000_VDDA")
		)
		(pad "2" smd circle
			(at -0.40005 0 270)
			(size 0 0)
			(layers "B.Cu" "B.Mask" "B.Paste")
			(net "GND")
		)
	)
)
